G04*
G04 #@! TF.GenerationSoftware,Altium Limited,Altium Designer,22.4.2 (48)*
G04*
G04 Layer_Physical_Order=1*
G04 Layer_Color=255*
%FSLAX25Y25*%
%MOIN*%
G70*
G04*
G04 #@! TF.SameCoordinates,B69760C6-9901-4916-8BAC-4CFDAA04743E*
G04*
G04*
G04 #@! TF.FilePolarity,Positive*
G04*
G01*
G75*
%ADD13C,0.02000*%
%ADD14C,0.00700*%
%ADD19R,0.01860X0.02288*%
%ADD20R,0.02288X0.01860*%
%ADD21R,0.01968X0.02362*%
%ADD22R,0.02362X0.01968*%
%ADD23R,0.19685X0.03937*%
%ADD24C,0.03937*%
%ADD25R,0.03150X0.03150*%
G04:AMPARAMS|DCode=26|XSize=15.75mil|YSize=33.47mil|CornerRadius=1.97mil|HoleSize=0mil|Usage=FLASHONLY|Rotation=180.000|XOffset=0mil|YOffset=0mil|HoleType=Round|Shape=RoundedRectangle|*
%AMROUNDEDRECTD26*
21,1,0.01575,0.02953,0,0,180.0*
21,1,0.01181,0.03347,0,0,180.0*
1,1,0.00394,-0.00591,0.01476*
1,1,0.00394,0.00591,0.01476*
1,1,0.00394,0.00591,-0.01476*
1,1,0.00394,-0.00591,-0.01476*
%
%ADD26ROUNDEDRECTD26*%
%ADD27R,0.03150X0.05906*%
%ADD28R,0.05906X0.03150*%
%ADD29R,0.04331X0.04331*%
%ADD30R,0.02441X0.02362*%
%ADD31R,0.02423X0.02254*%
G04:AMPARAMS|DCode=32|XSize=11.81mil|YSize=31.5mil|CornerRadius=1.95mil|HoleSize=0mil|Usage=FLASHONLY|Rotation=90.000|XOffset=0mil|YOffset=0mil|HoleType=Round|Shape=RoundedRectangle|*
%AMROUNDEDRECTD32*
21,1,0.01181,0.02760,0,0,90.0*
21,1,0.00791,0.03150,0,0,90.0*
1,1,0.00390,0.01380,0.00396*
1,1,0.00390,0.01380,-0.00396*
1,1,0.00390,-0.01380,-0.00396*
1,1,0.00390,-0.01380,0.00396*
%
%ADD32ROUNDEDRECTD32*%
%ADD33R,0.03150X0.03543*%
%ADD34R,0.02559X0.03347*%
%ADD35R,0.02254X0.02423*%
%ADD36R,0.01788X0.01428*%
%ADD37R,0.03937X0.03543*%
%ADD38R,0.02362X0.02441*%
%ADD39R,0.11614X0.04016*%
G04:AMPARAMS|DCode=40|XSize=11.81mil|YSize=31.5mil|CornerRadius=1.95mil|HoleSize=0mil|Usage=FLASHONLY|Rotation=0.000|XOffset=0mil|YOffset=0mil|HoleType=Round|Shape=RoundedRectangle|*
%AMROUNDEDRECTD40*
21,1,0.01181,0.02760,0,0,0.0*
21,1,0.00791,0.03150,0,0,0.0*
1,1,0.00390,0.00396,-0.01380*
1,1,0.00390,-0.00396,-0.01380*
1,1,0.00390,-0.00396,0.01380*
1,1,0.00390,0.00396,0.01380*
%
%ADD40ROUNDEDRECTD40*%
%ADD54C,0.00050*%
%ADD55C,0.00800*%
%ADD56C,0.00600*%
%ADD57C,0.01000*%
%ADD58C,0.02400*%
G36*
X260531Y123977D02*
X261155Y123852D01*
X261743Y123609D01*
X262272Y123256D01*
X262722Y122806D01*
X263076Y122277D01*
X263320Y121689D01*
X263445Y121065D01*
X263445Y120747D01*
X263433Y3996D01*
X263433Y3996D01*
X263433Y3996D01*
X263433Y3701D01*
X263318Y3124D01*
X263093Y2579D01*
X262766Y2090D01*
X262350Y1673D01*
X261860Y1345D01*
X261316Y1120D01*
X260738Y1004D01*
X260444Y1004D01*
X4114Y1020D01*
X4114Y1020D01*
X4114Y1020D01*
X3809D01*
X3212Y1139D01*
X2648Y1372D01*
X2142Y1710D01*
X1710Y2142D01*
X1372Y2648D01*
X1139Y3212D01*
X1020Y3809D01*
Y4114D01*
X1020Y4114D01*
X1020Y4114D01*
X1012Y120772D01*
X1012Y121086D01*
X1134Y121704D01*
X1375Y122285D01*
X1725Y122809D01*
X2169Y123254D01*
X2692Y123604D01*
X3274Y123845D01*
X3891Y123968D01*
X4206Y123969D01*
X260213Y123977D01*
X260531Y123977D01*
D02*
G37*
%LPC*%
G36*
X250014Y120886D02*
X248812D01*
X248714Y120866D01*
X248613D01*
X247434Y120632D01*
X247342Y120593D01*
X247243Y120574D01*
X246133Y120114D01*
X246049Y120058D01*
X245956Y120019D01*
X244957Y119351D01*
X244886Y119281D01*
X244802Y119225D01*
X243952Y118375D01*
X243897Y118291D01*
X243826Y118220D01*
X243158Y117221D01*
X243119Y117128D01*
X243064Y117044D01*
X242604Y115934D01*
X242584Y115835D01*
X242546Y115743D01*
X242311Y114564D01*
Y114463D01*
X242291Y114365D01*
Y113163D01*
X242311Y113064D01*
Y112964D01*
X242546Y111785D01*
X242584Y111692D01*
X242604Y111594D01*
X243064Y110483D01*
X243119Y110399D01*
X243158Y110307D01*
X243826Y109307D01*
X243897Y109236D01*
X243952Y109153D01*
X244802Y108303D01*
X244886Y108247D01*
X244957Y108176D01*
X245956Y107508D01*
X246049Y107470D01*
X246133Y107414D01*
X247243Y106954D01*
X247342Y106934D01*
X247434Y106896D01*
X248613Y106661D01*
X248714D01*
X248812Y106642D01*
X250014D01*
X250113Y106661D01*
X250213D01*
X251392Y106896D01*
X251485Y106934D01*
X251584Y106954D01*
X252694Y107414D01*
X252778Y107470D01*
X252870Y107508D01*
X253870Y108176D01*
X253941Y108247D01*
X254024Y108303D01*
X254874Y109153D01*
X254930Y109236D01*
X255001Y109307D01*
X255669Y110307D01*
X255707Y110399D01*
X255763Y110483D01*
X256223Y111594D01*
X256243Y111692D01*
X256281Y111785D01*
X256516Y112964D01*
Y113064D01*
X256535Y113163D01*
Y114365D01*
X256516Y114463D01*
Y114564D01*
X256281Y115743D01*
X256243Y115835D01*
X256223Y115934D01*
X255763Y117044D01*
X255707Y117128D01*
X255669Y117221D01*
X255001Y118220D01*
X254930Y118291D01*
X254874Y118375D01*
X254024Y119225D01*
X253941Y119281D01*
X253870Y119351D01*
X252870Y120019D01*
X252778Y120058D01*
X252694Y120114D01*
X251584Y120574D01*
X251485Y120593D01*
X251392Y120632D01*
X250213Y120866D01*
X250113D01*
X250014Y120886D01*
D02*
G37*
G36*
X11825D02*
X10623D01*
X10525Y120866D01*
X10424D01*
X9245Y120632D01*
X9153Y120593D01*
X9054Y120574D01*
X7944Y120114D01*
X7860Y120058D01*
X7767Y120019D01*
X6768Y119351D01*
X6697Y119281D01*
X6613Y119225D01*
X5763Y118375D01*
X5708Y118291D01*
X5637Y118220D01*
X4969Y117221D01*
X4930Y117128D01*
X4875Y117044D01*
X4415Y115934D01*
X4395Y115835D01*
X4357Y115743D01*
X4122Y114564D01*
Y114463D01*
X4103Y114365D01*
Y113163D01*
X4122Y113064D01*
Y112964D01*
X4357Y111785D01*
X4395Y111692D01*
X4415Y111594D01*
X4875Y110483D01*
X4930Y110399D01*
X4969Y110307D01*
X5637Y109307D01*
X5708Y109236D01*
X5763Y109153D01*
X6613Y108303D01*
X6697Y108247D01*
X6768Y108176D01*
X7767Y107508D01*
X7860Y107470D01*
X7944Y107414D01*
X9054Y106954D01*
X9153Y106934D01*
X9245Y106896D01*
X10424Y106661D01*
X10525D01*
X10623Y106642D01*
X11825D01*
X11924Y106661D01*
X12024D01*
X13203Y106896D01*
X13296Y106934D01*
X13395Y106954D01*
X14505Y107414D01*
X14589Y107470D01*
X14681Y107508D01*
X15681Y108176D01*
X15752Y108247D01*
X15835Y108303D01*
X16685Y109153D01*
X16741Y109236D01*
X16812Y109307D01*
X17480Y110307D01*
X17518Y110399D01*
X17574Y110483D01*
X18034Y111594D01*
X18054Y111692D01*
X18092Y111785D01*
X18327Y112964D01*
Y113064D01*
X18346Y113163D01*
Y114365D01*
X18327Y114463D01*
Y114564D01*
X18092Y115743D01*
X18054Y115835D01*
X18034Y115934D01*
X17574Y117044D01*
X17518Y117128D01*
X17480Y117221D01*
X16812Y118220D01*
X16741Y118291D01*
X16685Y118375D01*
X15835Y119225D01*
X15752Y119281D01*
X15681Y119351D01*
X14681Y120019D01*
X14589Y120058D01*
X14505Y120114D01*
X13395Y120574D01*
X13296Y120593D01*
X13203Y120632D01*
X12024Y120866D01*
X11924D01*
X11825Y120886D01*
D02*
G37*
G36*
X251275Y86723D02*
X246925D01*
Y85568D01*
X245228D01*
X244838Y85490D01*
X244507Y85269D01*
X240202Y80963D01*
X238370D01*
Y78485D01*
X237970D01*
Y76841D01*
X239900D01*
X241830D01*
Y78485D01*
X241430D01*
Y79308D01*
X245651Y83528D01*
X246925D01*
Y82373D01*
X251275D01*
Y86723D01*
D02*
G37*
G36*
X187400Y114420D02*
X111222D01*
X110832Y114342D01*
X110501Y114121D01*
X98464Y102084D01*
X98243Y101753D01*
X98166Y101363D01*
Y96592D01*
X97010D01*
Y89487D01*
X123013D01*
Y96592D01*
X122220D01*
Y100742D01*
X122220Y100743D01*
X122726Y101249D01*
X123000Y101910D01*
Y102627D01*
X122866Y102949D01*
X123201Y103449D01*
X123842D01*
X124232Y103526D01*
X124563Y103748D01*
X124818Y104002D01*
X125279Y103811D01*
Y102130D01*
X125680D01*
Y98908D01*
X127695D01*
X128378Y98224D01*
Y96592D01*
X127325D01*
Y89487D01*
X153328D01*
Y92020D01*
X163650D01*
X184243Y71427D01*
X183997Y70966D01*
X183668Y71031D01*
X164547D01*
X163922Y70907D01*
X163393Y70553D01*
X161376Y68537D01*
X161023Y68007D01*
X161003Y67910D01*
X160843Y67750D01*
X158387D01*
X157927Y67560D01*
X157737Y67101D01*
Y62750D01*
X151387D01*
X150927Y62560D01*
X150737Y62101D01*
Y58601D01*
X150927Y58141D01*
X150947Y58133D01*
Y54068D01*
X150927Y54060D01*
X150737Y53601D01*
Y45610D01*
X150927Y45151D01*
X151387Y44961D01*
X157785D01*
X159908Y44282D01*
Y44179D01*
X160230D01*
X160931Y43955D01*
X161023Y43492D01*
X161376Y42963D01*
X183728Y20612D01*
X177516Y14401D01*
X177068Y14660D01*
X177068Y14662D01*
Y15338D01*
X176893Y15991D01*
X176555Y16577D01*
X176077Y17055D01*
X175491Y17393D01*
X174838Y17569D01*
X174162D01*
X173509Y17393D01*
X172923Y17055D01*
X172445Y16577D01*
X172107Y15991D01*
X172009Y15627D01*
X171491D01*
X171394Y15991D01*
X171055Y16577D01*
X170577Y17055D01*
X169991Y17393D01*
X169338Y17569D01*
X168662D01*
X168009Y17393D01*
X167423Y17055D01*
X166945Y16577D01*
X166606Y15991D01*
X166509Y15627D01*
X165991D01*
X165893Y15991D01*
X165555Y16577D01*
X165077Y17055D01*
X164491Y17393D01*
X163838Y17569D01*
X163162D01*
X162509Y17393D01*
X161923Y17055D01*
X161445Y16577D01*
X161107Y15991D01*
X161032Y15712D01*
X153328D01*
Y18246D01*
X97010D01*
Y13038D01*
X96548Y12846D01*
X82663Y26732D01*
Y48200D01*
Y53931D01*
X82919Y54141D01*
X83949D01*
Y49981D01*
X83384D01*
Y46419D01*
X86553D01*
Y49981D01*
X85988D01*
Y54203D01*
X85989Y54203D01*
X86176Y54328D01*
X89213D01*
X89603Y54405D01*
X89934Y54626D01*
X91824Y56517D01*
X92286Y56325D01*
Y53857D01*
Y49526D01*
Y45195D01*
Y40865D01*
Y36534D01*
X99391D01*
Y40865D01*
Y45195D01*
Y49526D01*
Y53857D01*
Y58187D01*
Y62518D01*
Y66849D01*
Y71198D01*
X92286D01*
Y70320D01*
X86653D01*
Y71081D01*
X83484D01*
Y67519D01*
X84049D01*
Y63949D01*
X84127Y63559D01*
X84347Y63228D01*
X84655Y62921D01*
X84463Y62459D01*
X84411D01*
X83931Y62500D01*
X83807Y63124D01*
X83454Y63653D01*
X82763Y64344D01*
Y69300D01*
X82716Y69537D01*
Y71081D01*
X79547D01*
Y70721D01*
X77975D01*
Y70816D01*
X77526D01*
X77459Y71151D01*
X77105Y71681D01*
X75816Y72970D01*
X75287Y73323D01*
X75208Y73339D01*
X75191Y73356D01*
X74662Y73709D01*
X74038Y73834D01*
X61714D01*
X61714Y73834D01*
X61090Y73709D01*
X60561Y73356D01*
X58423Y71218D01*
X57850D01*
X57539Y71156D01*
X57276Y70980D01*
X57100Y70716D01*
X57038Y70406D01*
Y70170D01*
X56934Y70014D01*
X56810Y69390D01*
Y68929D01*
X56934Y68305D01*
X57038Y68149D01*
Y67453D01*
X57100Y67142D01*
X57276Y66878D01*
X57539Y66702D01*
X57850Y66640D01*
X58808D01*
X58828Y66636D01*
X59122D01*
X62642Y63116D01*
X62643Y63112D01*
X62483Y62568D01*
X62281Y62525D01*
X62058Y62675D01*
X61590Y62768D01*
X61500D01*
Y60071D01*
X60500D01*
Y62768D01*
X60409D01*
X59943Y62675D01*
X59547Y62410D01*
X59432Y62238D01*
X59342Y62298D01*
X59031Y62360D01*
X57850D01*
X57539Y62298D01*
X57362Y62179D01*
X56600Y62942D01*
X56600Y62942D01*
Y63658D01*
X56326Y64320D01*
X55820Y64826D01*
X55158Y65100D01*
X54442D01*
X53780Y64826D01*
X53631Y64677D01*
X53131Y64884D01*
Y72001D01*
X53227D01*
Y75493D01*
X53350Y75677D01*
X53409Y75976D01*
Y76791D01*
X72819D01*
Y76473D01*
X72879Y76174D01*
X73001Y75990D01*
Y75873D01*
X73118D01*
X73302Y75750D01*
X73601Y75691D01*
X76024D01*
X76323Y75750D01*
X76500Y75868D01*
X76676Y75750D01*
X76976Y75691D01*
X79399D01*
X79698Y75750D01*
X79882Y75873D01*
X79999D01*
Y75990D01*
X80121Y76174D01*
X80174Y76439D01*
X92103D01*
Y76110D01*
X92163Y75811D01*
X92286Y75627D01*
Y75510D01*
X92402D01*
X92586Y75387D01*
X92886Y75328D01*
X98791D01*
X99091Y75387D01*
X99275Y75510D01*
X99391D01*
Y75627D01*
X99514Y75811D01*
X99574Y76110D01*
Y79260D01*
X99514Y79559D01*
X99391Y79743D01*
Y79860D01*
X99275D01*
X99091Y79983D01*
X98791Y80042D01*
X92886D01*
X92586Y79983D01*
X92402Y79860D01*
X92286D01*
Y79743D01*
X92163Y79559D01*
X92103Y79260D01*
Y78761D01*
X80174D01*
X80121Y79026D01*
X79999Y79210D01*
Y79327D01*
X79882D01*
X79698Y79450D01*
X79399Y79509D01*
X76976D01*
X76676Y79450D01*
X76500Y79332D01*
X76323Y79450D01*
X76024Y79509D01*
X73601D01*
X73302Y79450D01*
X73118Y79327D01*
X73001D01*
Y79210D01*
X72937Y79114D01*
X52938D01*
X52926Y79121D01*
X52627Y79181D01*
X50373D01*
X50074Y79121D01*
X50062Y79114D01*
X44882D01*
X44879Y79117D01*
Y79234D01*
X44763D01*
X44579Y79357D01*
X44280Y79416D01*
X41721D01*
X41421Y79357D01*
X41237Y79234D01*
X41120D01*
Y79117D01*
X41118Y79114D01*
X26862D01*
X26856Y79146D01*
X26511Y79979D01*
X26454Y80064D01*
X26408Y80156D01*
X25859Y80871D01*
X25782Y80939D01*
X25715Y81016D01*
X24999Y81565D01*
X24908Y81610D01*
X24823Y81667D01*
X23990Y82012D01*
X23889Y82032D01*
X23792Y82065D01*
X22898Y82183D01*
X22796Y82176D01*
X22694Y82183D01*
X21800Y82065D01*
X21703Y82032D01*
X21602Y82012D01*
X20769Y81667D01*
X20684Y81610D01*
X20592Y81565D01*
X19877Y81016D01*
X19809Y80939D01*
X19733Y80871D01*
X19184Y80156D01*
X19138Y80064D01*
X19081Y79979D01*
X18736Y79146D01*
X18716Y79046D01*
X18683Y78949D01*
X18566Y78054D01*
X18572Y77952D01*
X18566Y77850D01*
X18683Y76956D01*
X18716Y76859D01*
X18736Y76759D01*
X19081Y75926D01*
X19138Y75841D01*
X19184Y75749D01*
X19733Y75033D01*
X19809Y74966D01*
X19877Y74889D01*
X20592Y74340D01*
X20684Y74295D01*
X20769Y74238D01*
X21602Y73893D01*
X21703Y73873D01*
X21800Y73840D01*
X22694Y73722D01*
X22796Y73729D01*
X22898Y73722D01*
X23792Y73840D01*
X23889Y73873D01*
X23990Y73893D01*
X24823Y74238D01*
X24908Y74295D01*
X24999Y74340D01*
X25715Y74889D01*
X25782Y74966D01*
X25859Y75033D01*
X26408Y75749D01*
X26454Y75841D01*
X26511Y75926D01*
X26856Y76759D01*
X26862Y76791D01*
X40938D01*
Y75287D01*
X40953Y75213D01*
X40720Y74713D01*
X40720D01*
Y72539D01*
X43000D01*
X45279D01*
Y74713D01*
X45279Y74713D01*
X45047Y75213D01*
X45062Y75287D01*
Y76791D01*
X49591D01*
Y75976D01*
X49650Y75677D01*
X49773Y75493D01*
Y72001D01*
X49869D01*
Y66714D01*
X49302D01*
Y65000D01*
Y63286D01*
X49869D01*
Y54521D01*
X48932D01*
Y49778D01*
X51565D01*
X52658Y48684D01*
X52467Y48222D01*
X48932D01*
Y43479D01*
X54068D01*
Y44369D01*
X57869D01*
Y36809D01*
X57325D01*
Y32065D01*
X61675D01*
Y36809D01*
X61131D01*
Y45676D01*
X61163Y45835D01*
Y46000D01*
X61116Y46237D01*
Y47781D01*
X58580D01*
X58250Y48281D01*
X58400Y48642D01*
Y49358D01*
X58126Y50020D01*
X57620Y50526D01*
X56958Y50800D01*
X56242D01*
X55835Y50631D01*
X55475D01*
X55290Y50873D01*
X55527Y51373D01*
X56813D01*
Y53000D01*
X55101D01*
Y51829D01*
X55101Y51562D01*
X54614Y51343D01*
X54068Y51888D01*
Y54521D01*
X53131D01*
Y61716D01*
X53631Y61923D01*
X53780Y61774D01*
X54442Y61500D01*
X55158D01*
X55158Y61500D01*
X56293Y60365D01*
X56624Y60144D01*
X57014Y60067D01*
X57038D01*
Y58595D01*
X57100Y58284D01*
X57276Y58020D01*
X57539Y57844D01*
X57850Y57782D01*
X59031D01*
X59342Y57844D01*
X59432Y57903D01*
X59547Y57732D01*
X59943Y57467D01*
X60409Y57374D01*
X60789D01*
X61000Y57058D01*
Y56342D01*
X61255Y55727D01*
X61074Y55227D01*
X59524D01*
Y55627D01*
X57813D01*
Y53500D01*
Y51373D01*
X59524D01*
Y51773D01*
X62019D01*
X62449Y51372D01*
X62449Y51294D01*
Y47781D01*
X61884D01*
Y46237D01*
X61837Y46000D01*
X61884Y45763D01*
Y44219D01*
X65053D01*
Y44369D01*
X67561D01*
X67795Y44415D01*
X68295Y44070D01*
Y44070D01*
X69939D01*
Y46000D01*
Y47930D01*
X68295D01*
Y47930D01*
X67795Y47585D01*
X67561Y47631D01*
X65053D01*
Y47781D01*
X64488D01*
Y50949D01*
X65044Y51505D01*
X65203Y51439D01*
X65919D01*
X66581Y51713D01*
X67087Y52219D01*
X67361Y52881D01*
Y53597D01*
X67087Y54258D01*
X66581Y54765D01*
X66259Y54898D01*
X66152Y55185D01*
X66122Y55496D01*
X66288Y55745D01*
X66366Y56135D01*
Y57281D01*
X66866Y57488D01*
X66880Y57474D01*
X67542Y57200D01*
X67958D01*
X68563Y56595D01*
X68894Y56374D01*
X69107Y55847D01*
X71701D01*
Y55347D01*
X72201D01*
Y53733D01*
X73081D01*
X73256Y53589D01*
Y34738D01*
X69265Y30746D01*
X61643D01*
X61253Y30669D01*
X60922Y30448D01*
X59368Y28894D01*
X59257Y28727D01*
X58435Y27905D01*
X57935Y28112D01*
Y28935D01*
X53585D01*
Y24191D01*
X54132D01*
Y22977D01*
X54256Y22353D01*
X54610Y21824D01*
X58817Y17617D01*
Y16650D01*
X59978D01*
X60487Y16549D01*
X60561D01*
X61070Y16650D01*
X61889D01*
X61932Y16437D01*
X62286Y15907D01*
X75747Y2447D01*
X76276Y2093D01*
X76900Y1969D01*
X211560D01*
X212185Y2093D01*
X212714Y2447D01*
X220228Y9961D01*
X220582Y10490D01*
X220706Y11114D01*
Y16673D01*
X220582Y17298D01*
X220302Y17717D01*
X220476Y18217D01*
X226048D01*
X226672Y18341D01*
X227202Y18695D01*
X235276Y26769D01*
X237900D01*
X238524Y26893D01*
X239054Y27246D01*
X241941Y30134D01*
X242983D01*
Y29991D01*
X255797D01*
Y35206D01*
X255448D01*
X255257Y35668D01*
X256918Y37329D01*
X257139Y37660D01*
X257216Y38050D01*
Y42895D01*
X257139Y43285D01*
X256918Y43615D01*
X256332Y44201D01*
X256332Y44201D01*
X255257Y45277D01*
X255448Y45739D01*
X255797D01*
Y50954D01*
X242983D01*
Y49366D01*
X240705D01*
X240315Y49288D01*
X239985Y49067D01*
X238345Y47428D01*
X237883Y47620D01*
Y50954D01*
X228401D01*
Y51086D01*
X228324Y51476D01*
X228103Y51807D01*
X227159Y52751D01*
X227350Y53213D01*
X230976D01*
Y56221D01*
Y59228D01*
X226327D01*
X226213Y59473D01*
X226174Y59728D01*
X226626Y60180D01*
X226900Y60842D01*
Y61558D01*
X226626Y62220D01*
X226120Y62726D01*
X226120Y62726D01*
Y72700D01*
X226042Y73090D01*
X225821Y73421D01*
X222844Y76398D01*
X222852Y76468D01*
X222903Y76647D01*
X223052Y76880D01*
X227288D01*
X244878Y59290D01*
X244687Y58828D01*
X242983D01*
Y53613D01*
X255797D01*
Y58828D01*
X250409D01*
Y75877D01*
X251275D01*
Y80227D01*
X246925D01*
Y75877D01*
X248370D01*
Y58828D01*
X247670D01*
Y58960D01*
X247592Y59350D01*
X247372Y59681D01*
X228431Y78621D01*
X228100Y78842D01*
X227710Y78920D01*
X223322D01*
X188121Y114121D01*
X187790Y114342D01*
X187400Y114420D01*
D02*
G37*
G36*
X241830Y75841D02*
X240400D01*
Y74198D01*
X241830D01*
Y75841D01*
D02*
G37*
G36*
X239400D02*
X237970D01*
Y74198D01*
X239400D01*
Y75841D01*
D02*
G37*
G36*
X158053Y79860D02*
X150947D01*
Y75510D01*
Y71179D01*
X158053D01*
Y75510D01*
Y79860D01*
D02*
G37*
G36*
X45279Y71539D02*
X43500D01*
Y69366D01*
X45279D01*
Y71539D01*
D02*
G37*
G36*
X42500D02*
X40720D01*
Y69366D01*
X42500D01*
Y71539D01*
D02*
G37*
G36*
X48302Y66714D02*
X46908D01*
Y65500D01*
X48302D01*
Y66714D01*
D02*
G37*
G36*
X33638Y63852D02*
X23295D01*
Y63503D01*
X33638D01*
Y63852D01*
D02*
G37*
G36*
X22295D02*
X11953D01*
Y63503D01*
X22295D01*
Y63852D01*
D02*
G37*
G36*
X48302Y64500D02*
X46908D01*
Y63286D01*
X48302D01*
Y64500D01*
D02*
G37*
G36*
X238283Y59228D02*
X231976D01*
Y56721D01*
X238283D01*
Y59228D01*
D02*
G37*
G36*
X56813Y55627D02*
X55101D01*
Y54000D01*
X56813D01*
Y55627D01*
D02*
G37*
G36*
X71201Y54847D02*
X69123D01*
X69195Y54485D01*
X69459Y54090D01*
X69855Y53826D01*
X70321Y53733D01*
X71201D01*
Y54847D01*
D02*
G37*
G36*
X238283Y55721D02*
X231976D01*
Y53213D01*
X238283D01*
Y55721D01*
D02*
G37*
G36*
X72583Y47930D02*
X70939D01*
Y46500D01*
X72583D01*
Y47930D01*
D02*
G37*
G36*
Y45500D02*
X70939D01*
Y44070D01*
X72583D01*
Y45500D01*
D02*
G37*
G36*
X99391Y32222D02*
X92286D01*
Y27872D01*
X99391D01*
Y32222D01*
D02*
G37*
G36*
X158053Y40883D02*
X150947D01*
Y36534D01*
Y32203D01*
Y27872D01*
Y23542D01*
X158053D01*
Y27872D01*
Y32203D01*
Y36534D01*
Y40883D01*
D02*
G37*
G36*
X250014Y18523D02*
X248812D01*
X248714Y18504D01*
X248613D01*
X247434Y18269D01*
X247342Y18231D01*
X247243Y18211D01*
X246133Y17751D01*
X246049Y17696D01*
X245956Y17657D01*
X244957Y16989D01*
X244886Y16918D01*
X244802Y16862D01*
X243952Y16013D01*
X243897Y15929D01*
X243826Y15858D01*
X243158Y14859D01*
X243119Y14766D01*
X243064Y14682D01*
X242604Y13572D01*
X242584Y13473D01*
X242546Y13381D01*
X242311Y12201D01*
Y12101D01*
X242291Y12003D01*
Y10801D01*
X242311Y10702D01*
Y10602D01*
X242546Y9423D01*
X242584Y9330D01*
X242604Y9231D01*
X243064Y8121D01*
X243119Y8037D01*
X243158Y7945D01*
X243826Y6945D01*
X243897Y6874D01*
X243952Y6791D01*
X244802Y5941D01*
X244886Y5885D01*
X244957Y5814D01*
X245956Y5146D01*
X246049Y5108D01*
X246133Y5052D01*
X247243Y4592D01*
X247342Y4572D01*
X247434Y4534D01*
X248613Y4299D01*
X248714D01*
X248812Y4280D01*
X250014D01*
X250113Y4299D01*
X250213D01*
X251392Y4534D01*
X251485Y4572D01*
X251584Y4592D01*
X252694Y5052D01*
X252778Y5108D01*
X252870Y5146D01*
X253870Y5814D01*
X253941Y5885D01*
X254024Y5941D01*
X254874Y6791D01*
X254930Y6874D01*
X255001Y6945D01*
X255669Y7945D01*
X255707Y8037D01*
X255763Y8121D01*
X256223Y9231D01*
X256243Y9330D01*
X256281Y9423D01*
X256516Y10602D01*
Y10702D01*
X256535Y10801D01*
Y12003D01*
X256516Y12101D01*
Y12201D01*
X256281Y13381D01*
X256243Y13473D01*
X256223Y13572D01*
X255763Y14682D01*
X255707Y14766D01*
X255669Y14859D01*
X255001Y15858D01*
X254930Y15929D01*
X254874Y16013D01*
X254024Y16862D01*
X253941Y16918D01*
X253870Y16989D01*
X252870Y17657D01*
X252778Y17696D01*
X252694Y17751D01*
X251584Y18211D01*
X251485Y18231D01*
X251392Y18269D01*
X250213Y18504D01*
X250113D01*
X250014Y18523D01*
D02*
G37*
G36*
X11825D02*
X10623D01*
X10525Y18504D01*
X10424D01*
X9245Y18269D01*
X9153Y18231D01*
X9054Y18211D01*
X7944Y17751D01*
X7860Y17696D01*
X7767Y17657D01*
X6768Y16989D01*
X6697Y16918D01*
X6613Y16862D01*
X5763Y16013D01*
X5708Y15929D01*
X5637Y15858D01*
X4969Y14859D01*
X4930Y14766D01*
X4875Y14682D01*
X4415Y13572D01*
X4395Y13473D01*
X4357Y13381D01*
X4122Y12201D01*
Y12101D01*
X4103Y12003D01*
Y10801D01*
X4122Y10702D01*
Y10602D01*
X4357Y9423D01*
X4395Y9330D01*
X4415Y9231D01*
X4875Y8121D01*
X4930Y8037D01*
X4969Y7945D01*
X5637Y6945D01*
X5708Y6874D01*
X5763Y6791D01*
X6613Y5941D01*
X6697Y5885D01*
X6768Y5814D01*
X7767Y5146D01*
X7860Y5108D01*
X7944Y5052D01*
X9054Y4592D01*
X9153Y4572D01*
X9245Y4534D01*
X10424Y4299D01*
X10525D01*
X10623Y4280D01*
X11825D01*
X11924Y4299D01*
X12024D01*
X13203Y4534D01*
X13296Y4572D01*
X13395Y4592D01*
X14505Y5052D01*
X14589Y5108D01*
X14681Y5146D01*
X15681Y5814D01*
X15752Y5885D01*
X15835Y5941D01*
X16685Y6791D01*
X16741Y6874D01*
X16812Y6945D01*
X17480Y7945D01*
X17518Y8037D01*
X17574Y8121D01*
X18034Y9231D01*
X18054Y9330D01*
X18092Y9423D01*
X18327Y10602D01*
Y10702D01*
X18346Y10801D01*
Y12003D01*
X18327Y12101D01*
Y12201D01*
X18092Y13381D01*
X18054Y13473D01*
X18034Y13572D01*
X17574Y14682D01*
X17518Y14766D01*
X17480Y14859D01*
X16812Y15858D01*
X16741Y15929D01*
X16685Y16013D01*
X15835Y16862D01*
X15752Y16918D01*
X15681Y16989D01*
X14681Y17657D01*
X14589Y17696D01*
X14505Y17751D01*
X13395Y18211D01*
X13296Y18231D01*
X13203Y18269D01*
X12024Y18504D01*
X11924D01*
X11825Y18523D01*
D02*
G37*
%LPD*%
G36*
X136033Y111880D02*
X135900Y111558D01*
Y110842D01*
X136174Y110180D01*
X136335Y110020D01*
X136128Y109520D01*
X124900D01*
X124510Y109442D01*
X124179Y109221D01*
X122702Y107744D01*
X122220Y108226D01*
X121558Y108500D01*
X120842D01*
X120180Y108226D01*
X119674Y107720D01*
X119400Y107058D01*
Y106342D01*
X119547Y105988D01*
X119213Y105488D01*
X105405D01*
X105214Y105950D01*
X111644Y112380D01*
X135699D01*
X136033Y111880D01*
D02*
G37*
G36*
X131719Y102884D02*
X135281D01*
Y103449D01*
X136063D01*
X136174Y103180D01*
X136680Y102674D01*
X137342Y102400D01*
X137564D01*
X137948Y101900D01*
X137932Y101838D01*
Y101162D01*
X138098Y100540D01*
X137441Y99882D01*
X137220Y99552D01*
X137142Y99161D01*
Y96592D01*
X130622D01*
Y98689D01*
X130622Y98689D01*
X130578Y98910D01*
X130897Y99410D01*
X131719D01*
Y98947D01*
X135281D01*
Y102116D01*
X131719D01*
Y101653D01*
X129776D01*
X129720Y102130D01*
X129720D01*
Y103811D01*
X127500D01*
Y104811D01*
X129720D01*
Y105473D01*
X131719D01*
Y102884D01*
D02*
G37*
G36*
X23788Y81222D02*
X24407Y80965D01*
X24963Y80593D01*
X25437Y80120D01*
X25809Y79563D01*
X26065Y78944D01*
X26196Y78287D01*
Y77952D01*
Y77618D01*
X26065Y76961D01*
X25809Y76342D01*
X25437Y75785D01*
X24963Y75311D01*
X24407Y74939D01*
X23788Y74683D01*
X23131Y74552D01*
X22461D01*
X21804Y74683D01*
X21185Y74939D01*
X20629Y75311D01*
X20155Y75785D01*
X19783Y76342D01*
X19527Y76961D01*
X19396Y77618D01*
Y77952D01*
Y78287D01*
X19527Y78944D01*
X19783Y79563D01*
X20155Y80120D01*
X20629Y80593D01*
X21185Y80965D01*
X21804Y81222D01*
X22461Y81352D01*
X23131D01*
X23788Y81222D01*
D02*
G37*
G36*
X207871Y74287D02*
X207753Y73698D01*
X207580Y73626D01*
X207074Y73120D01*
X206800Y72458D01*
Y71742D01*
X206887Y71531D01*
X206553Y71031D01*
X198983D01*
X198359Y70907D01*
X197829Y70553D01*
X196658Y69382D01*
X196304Y68853D01*
X196180Y68228D01*
Y66397D01*
X196304Y65773D01*
X196500Y65479D01*
Y65442D01*
X196774Y64780D01*
X197280Y64274D01*
X197942Y64000D01*
X198658D01*
X199320Y64274D01*
X199826Y64780D01*
X200100Y65442D01*
Y66158D01*
X199826Y66820D01*
X199443Y67203D01*
Y67553D01*
X199659Y67769D01*
X210619D01*
Y66984D01*
X212061D01*
X212219Y66953D01*
X212384D01*
X212542Y66984D01*
X214181D01*
Y67324D01*
X214643Y67515D01*
X217682Y64476D01*
X218013Y64255D01*
X218319Y64194D01*
Y63047D01*
X219080D01*
Y54683D01*
X218270D01*
Y53187D01*
X218066Y53147D01*
X217735Y52926D01*
X217149Y52340D01*
X216928Y52009D01*
X216850Y51619D01*
Y41292D01*
X215478Y39920D01*
X205010D01*
X204183Y40747D01*
X204231Y41083D01*
X204322Y41315D01*
X204521Y41448D01*
X204697Y41711D01*
X204709Y41769D01*
X206819D01*
X207159Y41628D01*
X207875D01*
X208216Y41769D01*
X208678D01*
Y41673D01*
X211653D01*
Y41273D01*
X213364D01*
Y43400D01*
Y45527D01*
X211653D01*
Y45127D01*
X208678D01*
Y45127D01*
X208178Y45102D01*
X207875Y45228D01*
X207159D01*
X206685Y45031D01*
X205138D01*
X205024Y45107D01*
X204634Y45185D01*
X204521Y45354D01*
X204259Y45529D01*
X203948Y45591D01*
X203157D01*
X202847Y45529D01*
X202584Y45354D01*
X202553D01*
X202290Y45529D01*
X201980Y45591D01*
X201189D01*
X200878Y45529D01*
X200848Y45509D01*
X200469Y45647D01*
X200366Y46175D01*
X203233Y49041D01*
X210070D01*
Y48317D01*
X213130D01*
Y49813D01*
X213334Y49853D01*
X213665Y50074D01*
X214251Y50660D01*
X214472Y50991D01*
X214550Y51381D01*
Y54497D01*
X214472Y54887D01*
X214251Y55218D01*
X213420Y56050D01*
Y63047D01*
X214181D01*
Y66216D01*
X210619D01*
Y63047D01*
X211380D01*
Y55627D01*
X211458Y55237D01*
X211472Y55216D01*
X211084Y54897D01*
X206686Y59295D01*
X206355Y59516D01*
X205965Y59594D01*
X200694D01*
X200304Y59516D01*
X199973Y59295D01*
X199616Y58938D01*
X164794Y93760D01*
X164463Y93981D01*
X164073Y94059D01*
X153328D01*
Y94801D01*
X153348Y94900D01*
X153328Y94999D01*
Y96592D01*
X149272D01*
X149086Y97028D01*
X149377Y97380D01*
X184778D01*
X207871Y74287D01*
D02*
G37*
G36*
X162887Y45101D02*
X163530Y44457D01*
Y44179D01*
X163808D01*
X164487Y43501D01*
X157887Y45610D01*
X151387D01*
Y53601D01*
X157887D01*
Y53857D01*
X158053D01*
Y58206D01*
X157887D01*
Y58601D01*
X151387D01*
Y62101D01*
X158387D01*
Y67101D01*
X162887D01*
Y45101D01*
D02*
G37*
G36*
X225069Y29991D02*
X233201D01*
X233338Y29746D01*
X233383Y29491D01*
X225372Y21479D01*
X218075D01*
Y22023D01*
X213725D01*
Y17673D01*
X215768D01*
X217414Y16027D01*
X217373Y15527D01*
X213725D01*
Y13484D01*
X213514Y13273D01*
X210062D01*
Y14020D01*
X208132D01*
X206202D01*
Y12376D01*
X206202D01*
X206548Y11876D01*
X206501Y11642D01*
X206602Y11132D01*
Y9898D01*
X209662D01*
Y10010D01*
X214190D01*
X214814Y10134D01*
X215343Y10488D01*
X215752Y10897D01*
X215828Y10882D01*
X215993Y10339D01*
X210885Y5231D01*
X173679D01*
X173601Y5328D01*
X173703Y5998D01*
X173776Y6047D01*
X185946Y18217D01*
X197993D01*
Y17673D01*
X202343D01*
Y22023D01*
X201799D01*
Y24792D01*
X207974Y30967D01*
X225069D01*
Y29991D01*
D02*
G37*
G36*
X185400Y65361D02*
Y65342D01*
X185674Y64680D01*
X186180Y64174D01*
X186842Y63900D01*
X187558D01*
X188220Y64174D01*
X188726Y64680D01*
X189000Y65342D01*
Y65963D01*
X189268Y66145D01*
X189462Y66208D01*
X196709Y58961D01*
X196589Y58374D01*
X196390Y58241D01*
X196126Y57845D01*
X196033Y57379D01*
Y56499D01*
X197647D01*
Y55999D01*
X198147D01*
Y53422D01*
X198509Y53494D01*
X198904Y53758D01*
X198971Y53858D01*
X199220Y53809D01*
X200011D01*
X200322Y53870D01*
X200355Y53890D01*
X200724Y53750D01*
X200829Y53236D01*
X200827Y53218D01*
X195279Y47671D01*
X195058Y47340D01*
X194980Y46949D01*
Y41000D01*
X195058Y40610D01*
X195279Y40279D01*
X200579Y34979D01*
X200910Y34758D01*
X201300Y34680D01*
X206128D01*
X206335Y34180D01*
X205991Y33837D01*
X205823Y33430D01*
X199014Y26621D01*
X198661Y26092D01*
X198536Y25468D01*
Y22023D01*
X197993D01*
Y21479D01*
X187474D01*
X165636Y43318D01*
X165828Y43780D01*
X167492D01*
Y45500D01*
X165311D01*
Y46000D01*
X164811D01*
Y48221D01*
X163536D01*
Y49279D01*
X164811D01*
Y51500D01*
Y53720D01*
X163536D01*
Y57780D01*
X164811D01*
Y60000D01*
Y62221D01*
X163536D01*
Y63279D01*
X164811D01*
Y65500D01*
X165311D01*
Y66000D01*
X167492D01*
Y67721D01*
X167972Y67769D01*
X182993D01*
X185400Y65361D01*
D02*
G37*
G36*
X73289Y66962D02*
X75000D01*
Y67362D01*
X77975D01*
Y67458D01*
X79500D01*
Y63669D01*
X79624Y63044D01*
X79978Y62515D01*
X80443Y62050D01*
X79878Y61484D01*
X79524Y60955D01*
X79400Y60330D01*
Y48200D01*
Y26056D01*
X79524Y25432D01*
X79878Y24903D01*
X98734Y6047D01*
X98807Y5998D01*
X98909Y5328D01*
X98831Y5231D01*
X77576D01*
X65183Y17624D01*
Y19710D01*
X65070D01*
Y24191D01*
X65415D01*
Y28707D01*
X69687D01*
X70077Y28785D01*
X70408Y29006D01*
X74997Y33594D01*
X75218Y33925D01*
X75295Y34315D01*
Y58206D01*
X75218Y58596D01*
X74997Y58927D01*
X74297Y59627D01*
X74050Y59792D01*
X74027Y59815D01*
X73936Y59875D01*
X73893Y59938D01*
X73753Y60419D01*
X73830Y60547D01*
X73891Y60857D01*
Y61648D01*
X73830Y61959D01*
X73654Y62221D01*
X73391Y62397D01*
X73081Y62459D01*
X72720D01*
Y64099D01*
X72643Y64489D01*
X72422Y64820D01*
X71300Y65942D01*
X71300Y65942D01*
Y66658D01*
X71503Y66962D01*
X72289D01*
Y69089D01*
X73289D01*
Y66962D01*
D02*
G37*
%LPC*%
G36*
X216075Y45527D02*
X214364D01*
Y43900D01*
X216075D01*
Y45527D01*
D02*
G37*
G36*
Y42900D02*
X214364D01*
Y41273D01*
X216075D01*
Y42900D01*
D02*
G37*
G36*
X210062Y16664D02*
X208632D01*
Y15020D01*
X210062D01*
Y16664D01*
D02*
G37*
G36*
X194330D02*
X192900D01*
Y15020D01*
X194330D01*
Y16664D01*
D02*
G37*
G36*
X207632D02*
X206202D01*
Y15020D01*
X207632D01*
Y16664D01*
D02*
G37*
G36*
X191900D02*
X190470D01*
Y15020D01*
X191900D01*
Y16664D01*
D02*
G37*
G36*
X202343Y15527D02*
X197993D01*
Y13484D01*
X197782Y13273D01*
X194330D01*
Y14020D01*
X192400D01*
X190470D01*
Y12376D01*
X190470D01*
X190815Y11876D01*
X190769Y11642D01*
X190870Y11132D01*
Y9898D01*
X193930D01*
Y10010D01*
X198457D01*
X199082Y10134D01*
X199611Y10488D01*
X200300Y11177D01*
X202343D01*
Y15527D01*
D02*
G37*
G36*
X167492Y65000D02*
X165811D01*
Y63279D01*
X167492D01*
Y65000D01*
D02*
G37*
G36*
Y62221D02*
X165811D01*
Y60500D01*
X167492D01*
Y62221D01*
D02*
G37*
G36*
Y59500D02*
X165811D01*
Y57780D01*
X167492D01*
Y59500D01*
D02*
G37*
G36*
X197147Y55499D02*
X196033D01*
Y54619D01*
X196126Y54153D01*
X196390Y53758D01*
X196785Y53494D01*
X197147Y53422D01*
Y55499D01*
D02*
G37*
G36*
X167492Y53720D02*
X165811D01*
Y52000D01*
X167492D01*
Y53720D01*
D02*
G37*
G36*
Y51000D02*
X165811D01*
Y49279D01*
X167492D01*
Y51000D01*
D02*
G37*
G36*
Y48221D02*
X165811D01*
Y46500D01*
X167492D01*
Y48221D01*
D02*
G37*
%LPD*%
D13*
X198300Y65800D02*
Y65908D01*
X197811Y66397D02*
X198300Y65908D01*
X197811Y66397D02*
Y68228D01*
X198983Y69400D02*
X210795D01*
X197811Y68228D02*
X198983Y69400D01*
X208945Y72023D02*
X211182Y69787D01*
X212219Y68750D01*
X187200Y65700D02*
Y65808D01*
X187000Y66008D02*
X187200Y65808D01*
X187000Y66008D02*
Y66069D01*
X183668Y69400D02*
X187000Y66069D01*
X164547Y69400D02*
X183668D01*
X76079Y69089D02*
X80375D01*
X204600Y43400D02*
X210490D01*
X74663Y71816D02*
X75952Y70527D01*
X74424Y71816D02*
X74663D01*
X74038Y72202D02*
X74424Y71816D01*
X61714Y72202D02*
X74038D01*
X59114Y69602D02*
X61714Y72202D01*
X172622Y7200D02*
X185271Y19848D01*
X81032Y26056D02*
X99888Y7200D01*
X172622D01*
X51500Y52150D02*
Y73813D01*
X52469Y51181D02*
X54650Y49000D01*
X56600D01*
X51500Y52150D02*
X51697D01*
X52469Y51378D01*
Y51181D02*
Y51378D01*
X75952Y69216D02*
X76079Y69089D01*
X58653Y69602D02*
X59114D01*
X75952Y69216D02*
Y70527D01*
X58441Y69390D02*
X58653Y69602D01*
X58441Y68929D02*
Y69390D01*
X81132Y63669D02*
X82300Y62500D01*
X81132Y69135D02*
Y69300D01*
Y63669D02*
Y69135D01*
X80375Y69089D02*
X80404Y69119D01*
X81116D02*
X81132Y69135D01*
X80404Y69119D02*
X81116D01*
X81032Y60330D02*
X82176Y61475D01*
X81032Y48200D02*
Y60330D01*
X186799Y19848D02*
X200168D01*
X185271D02*
X186799D01*
X81032Y26056D02*
Y48200D01*
X63439Y17061D02*
X76900Y3600D01*
X211560D02*
X219075Y11114D01*
X76900Y3600D02*
X211560D01*
X63468Y46000D02*
X67561D01*
X51500Y52150D02*
X51500Y52150D01*
X51500Y45850D02*
X51650Y46000D01*
X59531D01*
X59500Y45803D02*
X59531Y45835D01*
X59500Y34437D02*
Y45803D01*
X59531Y45835D02*
Y46000D01*
X60347Y18320D02*
X60487Y18180D01*
X60347Y18320D02*
Y18394D01*
X55764Y22977D02*
X60347Y18394D01*
X60487Y18180D02*
X60561D01*
X55764Y22977D02*
Y26559D01*
X55760Y26563D02*
X55764Y26559D01*
X63439Y17061D02*
Y18180D01*
Y26364D01*
X63240Y26563D02*
X63439Y26364D01*
X208677Y72023D02*
X208945D01*
X208600Y72100D02*
X208677Y72023D01*
X200168Y19848D02*
Y25468D01*
X207517Y32817D01*
X207844Y32598D02*
X231476D01*
X207625Y32817D02*
X207844Y32598D01*
X207517Y32817D02*
X207625D01*
X212219Y68584D02*
Y68750D01*
Y68584D02*
X212384D01*
X161689Y65500D02*
X161870Y65681D01*
Y66470D01*
X162530Y67130D01*
Y67383D01*
X164547Y69400D01*
X219919Y68584D02*
X219935Y68568D01*
X217200Y72100D02*
X219919Y69381D01*
X219935Y68568D02*
X220100D01*
X219919Y68584D02*
Y69381D01*
X204400Y43600D02*
X204600Y43400D01*
X234600Y28400D02*
X237900D01*
X215900Y19848D02*
X226048D01*
X234600Y28400D01*
X215900Y19848D02*
X219075Y16673D01*
X241265Y31765D02*
X248557D01*
X237900Y28400D02*
X241265Y31765D01*
X248557D02*
X249390Y32598D01*
X214190Y11642D02*
X215900Y13352D01*
X208132Y11642D02*
X214190D01*
X192400D02*
X198457D01*
X200168Y13352D01*
X162530Y44117D02*
X186799Y19848D01*
X162530Y44117D02*
Y45120D01*
X161689Y45961D02*
X162530Y45120D01*
X161689Y45961D02*
Y46000D01*
X219075Y11114D02*
Y16673D01*
D14*
X95754Y77600D02*
X95839Y77685D01*
X78187Y77600D02*
X95754D01*
X26196Y77952D02*
X74460D01*
X22796D02*
X26196D01*
X74460D02*
X74813Y77600D01*
D19*
X208132Y14520D02*
D03*
Y11642D02*
D03*
X239900Y79220D02*
D03*
Y76341D02*
D03*
X192400Y14520D02*
D03*
Y11642D02*
D03*
X211600Y52939D02*
D03*
Y50061D02*
D03*
X219800D02*
D03*
Y52939D02*
D03*
D20*
X63439Y18180D02*
D03*
X60561D02*
D03*
X70439Y46000D02*
D03*
X67561D02*
D03*
D21*
X84969Y48200D02*
D03*
X81032D02*
D03*
X81132Y69300D02*
D03*
X85069D02*
D03*
X63468Y46000D02*
D03*
X59531D02*
D03*
D22*
X212400Y68568D02*
D03*
Y64631D02*
D03*
X220100Y68568D02*
D03*
Y64631D02*
D03*
X133500Y100531D02*
D03*
Y104469D02*
D03*
D23*
X22795Y66472D02*
D03*
X21795Y88953D02*
D03*
D24*
X22796Y77952D02*
D03*
X146000Y101500D02*
D03*
X140500D02*
D03*
X116500D02*
D03*
X111000D02*
D03*
X105500D02*
D03*
X174500Y15000D02*
D03*
X169000D02*
D03*
X163500D02*
D03*
D25*
X249100Y84548D02*
D03*
Y78052D02*
D03*
X200168Y19848D02*
D03*
Y13352D02*
D03*
X215900D02*
D03*
Y19848D02*
D03*
D26*
X58441Y68929D02*
D03*
X63559D02*
D03*
Y60071D02*
D03*
X61000D02*
D03*
X58441D02*
D03*
D27*
X151154Y93039D02*
D03*
X146823D02*
D03*
X142492D02*
D03*
X138161D02*
D03*
X133831D02*
D03*
X129500D02*
D03*
X125169D02*
D03*
X112177D02*
D03*
X107846D02*
D03*
X103516D02*
D03*
X116508D02*
D03*
X120839D02*
D03*
X99185D02*
D03*
Y14693D02*
D03*
X103516D02*
D03*
X107846D02*
D03*
X112177D02*
D03*
X116508D02*
D03*
X120839D02*
D03*
X125169D02*
D03*
X129500D02*
D03*
X133831D02*
D03*
X138161D02*
D03*
X142492D02*
D03*
X146823D02*
D03*
X151154D02*
D03*
D28*
X95839Y82016D02*
D03*
Y77685D02*
D03*
Y73354D02*
D03*
Y69024D02*
D03*
Y64693D02*
D03*
Y60362D02*
D03*
Y56032D02*
D03*
Y51701D02*
D03*
Y47370D02*
D03*
Y43039D02*
D03*
Y38709D02*
D03*
Y34378D02*
D03*
Y30047D02*
D03*
Y25717D02*
D03*
X154500D02*
D03*
Y30047D02*
D03*
Y34378D02*
D03*
Y38709D02*
D03*
Y43039D02*
D03*
Y47370D02*
D03*
Y51701D02*
D03*
Y56032D02*
D03*
Y60362D02*
D03*
Y64693D02*
D03*
Y69024D02*
D03*
Y73354D02*
D03*
Y77685D02*
D03*
Y82016D02*
D03*
D29*
X104500Y24929D02*
D03*
Y33197D02*
D03*
Y41465D02*
D03*
Y49732D02*
D03*
Y58000D02*
D03*
Y66268D02*
D03*
Y74535D02*
D03*
X104500Y82803D02*
D03*
X112768Y24929D02*
D03*
Y33197D02*
D03*
Y41465D02*
D03*
Y49732D02*
D03*
Y58000D02*
D03*
Y66268D02*
D03*
Y74535D02*
D03*
X112768Y82803D02*
D03*
X121035Y24929D02*
D03*
Y33197D02*
D03*
Y41465D02*
D03*
Y49732D02*
D03*
Y58000D02*
D03*
Y66268D02*
D03*
Y74535D02*
D03*
X121035Y82803D02*
D03*
X129303Y24929D02*
D03*
Y33197D02*
D03*
Y41465D02*
D03*
Y49732D02*
D03*
Y58000D02*
D03*
Y66268D02*
D03*
Y74535D02*
D03*
X129303Y82803D02*
D03*
X137571Y24929D02*
D03*
Y33197D02*
D03*
Y41465D02*
D03*
Y49732D02*
D03*
Y58000D02*
D03*
Y66268D02*
D03*
Y74535D02*
D03*
X137571Y82803D02*
D03*
X145838Y24929D02*
D03*
Y33197D02*
D03*
Y41465D02*
D03*
Y49732D02*
D03*
Y58000D02*
D03*
Y66268D02*
D03*
Y74535D02*
D03*
X145838Y82803D02*
D03*
D30*
X127500Y104311D02*
D03*
Y100689D02*
D03*
D31*
X76163Y69089D02*
D03*
X72789D02*
D03*
X210490Y43400D02*
D03*
X213864D02*
D03*
X78187Y77600D02*
D03*
X74813D02*
D03*
X60687Y53500D02*
D03*
X57313D02*
D03*
D32*
X84299Y55347D02*
D03*
Y57316D02*
D03*
Y59284D02*
D03*
Y61253D02*
D03*
X71701Y55347D02*
D03*
Y57316D02*
D03*
Y59284D02*
D03*
Y61253D02*
D03*
D33*
X55760Y26563D02*
D03*
X63240D02*
D03*
X59500Y34437D02*
D03*
D34*
X43000Y72039D02*
D03*
Y76961D02*
D03*
D35*
X51500Y73813D02*
D03*
Y77187D02*
D03*
D36*
X51198Y65000D02*
D03*
X48802D02*
D03*
D37*
X51500Y45850D02*
D03*
Y52150D02*
D03*
D38*
X161689Y46000D02*
D03*
X165311D02*
D03*
Y51500D02*
D03*
X161689D02*
D03*
X165311Y60000D02*
D03*
X161689D02*
D03*
Y65500D02*
D03*
X165311D02*
D03*
D39*
X249390Y32598D02*
D03*
Y40472D02*
D03*
Y48346D02*
D03*
Y56221D02*
D03*
X231476Y32598D02*
D03*
Y40472D02*
D03*
Y48346D02*
D03*
Y56221D02*
D03*
D40*
X197647Y43401D02*
D03*
X199616D02*
D03*
X201584D02*
D03*
X203553D02*
D03*
X197647Y55999D02*
D03*
X199616D02*
D03*
X201584D02*
D03*
X203553D02*
D03*
D54*
X26196Y77952D02*
G03*
X26196Y77952I-3400J0D01*
G01*
X16334Y73152D02*
G03*
X29258Y73152I6462J4800D01*
G01*
Y82752D02*
G03*
X16334Y82752I-6462J-4800D01*
G01*
X8796Y92052D02*
X36796D01*
X29258Y73152D02*
X36796D01*
Y82752D02*
Y92052D01*
X8796Y82752D02*
Y92052D01*
X29258Y82752D02*
X36796D01*
X8796Y63852D02*
Y73152D01*
Y82752D02*
X16334D01*
X8796Y73152D02*
X16334D01*
X36796Y63852D02*
Y73152D01*
X8796Y63852D02*
X36796D01*
D55*
X213864Y45664D02*
X215400Y47200D01*
X213864Y43400D02*
Y45664D01*
X111222Y113400D02*
X187400D01*
X99185Y101363D02*
X111222Y113400D01*
X125279Y102284D02*
X126176Y103180D01*
X126330D01*
X127461Y104311D01*
X127500D01*
X125279Y93150D02*
Y102284D01*
X125169Y93039D02*
X125279Y93150D01*
X123842Y104469D02*
X125865Y106492D01*
X104270Y104469D02*
X123842D01*
X125865Y106492D02*
X145206D01*
X102532Y102730D02*
X104270Y104469D01*
X147998Y11209D02*
Y13518D01*
X146823Y14693D02*
X147998Y13518D01*
X120250Y9340D02*
X168840D01*
X174500Y15000D01*
X163438Y10740D02*
X167098Y14400D01*
X147998Y11209D02*
X148466Y10740D01*
X118264Y11326D02*
X120250Y9340D01*
X148466Y10740D02*
X163438D01*
X197646Y56000D02*
X197647Y55999D01*
X193900Y56000D02*
X197646D01*
X225100Y61200D02*
Y72700D01*
X222063Y75737D02*
X225100Y72700D01*
X220343Y75737D02*
X222063D01*
X218280Y77800D02*
X220343Y75737D01*
X68546Y58054D02*
X69284Y57316D01*
X71701D01*
X68100Y59106D02*
Y64388D01*
X64780Y67708D02*
X68100Y64388D01*
X117683Y11907D02*
Y13518D01*
X116508Y14693D02*
X117683Y13518D01*
Y11907D02*
X118264Y11326D01*
Y11326D02*
Y11326D01*
X60089Y28117D02*
Y28172D01*
X61643Y29727D01*
X69687D01*
X74276Y34315D02*
Y58206D01*
X69687Y29727D02*
X74276Y34315D01*
X55760Y26563D02*
X58535D01*
X73576Y58906D02*
X74276Y58206D01*
X73494Y58906D02*
X73576D01*
X73306Y59094D02*
X73494Y58906D01*
X58535Y26563D02*
X60089Y28117D01*
X71701Y59284D02*
X71891Y59094D01*
X73306D01*
X65346Y56135D02*
Y62043D01*
X63099Y53887D02*
X65346Y56135D01*
X61075Y53887D02*
X63099D01*
X60687Y53500D02*
X61075Y53887D01*
X62800Y56700D02*
Y57133D01*
X63219Y57552D02*
Y59731D01*
X63559Y60071D01*
X63468Y51372D02*
X65336Y53239D01*
X63468Y46000D02*
Y51372D01*
X62800Y57133D02*
X63219Y57552D01*
X54800Y63300D02*
X57014Y61086D01*
X58441Y60071D02*
Y60699D01*
X58053Y61086D02*
X58441Y60699D01*
X57014Y61086D02*
X58053D01*
X71701Y61253D02*
Y64099D01*
X69500Y66300D02*
X71701Y64099D01*
X63946Y67708D02*
X64780D01*
X63559Y68095D02*
X63946Y67708D01*
X63559Y68095D02*
Y68929D01*
X58441Y68043D02*
X58828Y67656D01*
X59544D01*
X64456Y62744D01*
X58441Y68043D02*
Y68929D01*
X64645Y62744D02*
X65346Y62043D01*
X64456Y62744D02*
X64645D01*
X57781Y56798D02*
X59776D01*
X60803Y57825D01*
Y59874D02*
X61000Y60071D01*
X57313Y53500D02*
Y56329D01*
X57781Y56798D01*
X60803Y57825D02*
Y59874D01*
X86185Y57694D02*
X92199Y63708D01*
X94853D02*
X95839Y64693D01*
X92199Y63708D02*
X94853D01*
X85943Y57694D02*
X86185D01*
X85755Y57506D02*
X85943Y57694D01*
X84299Y57316D02*
X84490Y57506D01*
X85755D01*
X84778Y55347D02*
X89213D01*
X84299D02*
X84778D01*
X93053Y59187D02*
X94664D01*
X95839Y60362D01*
X89213Y55347D02*
X93053Y59187D01*
X84778Y55347D02*
X84969Y55157D01*
Y48200D02*
Y55157D01*
X95562Y69300D02*
X95839Y69024D01*
X85069Y69300D02*
X95562D01*
X84490Y59475D02*
X85755D01*
X86174Y59662D02*
X86874Y60362D01*
X85069Y63949D02*
X86874Y62143D01*
X85069Y63949D02*
Y69300D01*
X84299Y59284D02*
X84490Y59475D01*
X85755D02*
X85943Y59662D01*
X86174D01*
X86874Y60362D02*
Y62143D01*
X167098Y14400D02*
X168400D01*
X169000Y15000D01*
X163193Y14693D02*
X163500Y15000D01*
X151154Y14693D02*
X163193D01*
X217094Y80306D02*
X217400Y80000D01*
X216194Y80306D02*
X217094D01*
X185300Y111200D02*
X216194Y80306D01*
X137700Y111200D02*
X185300D01*
X146198Y105500D02*
X182500D01*
X212500Y75500D02*
X218100D01*
X182500Y105500D02*
X212500Y75500D01*
X148954Y98400D02*
X185200D01*
X219534Y65197D02*
X220100Y64631D01*
X210248Y74300D02*
X214581Y69967D01*
X209300Y74300D02*
X210248D01*
X185200Y98400D02*
X209300Y74300D01*
X218403Y65197D02*
X219534D01*
X214581Y69019D02*
X218403Y65197D01*
X214581Y69019D02*
Y69967D01*
X214500Y77800D02*
X218280D01*
X183800Y108500D02*
X214500Y77800D01*
X124900Y108500D02*
X183800D01*
X145206Y106492D02*
X146198Y105500D01*
X227710Y77900D02*
X246651Y58960D01*
Y57828D02*
Y58960D01*
X222900Y77900D02*
X227710D01*
X187400Y113400D02*
X222900Y77900D01*
X248258Y56221D02*
X249390D01*
X99185Y93039D02*
Y101363D01*
X246651Y57828D02*
X248258Y56221D01*
X133500Y104469D02*
X137432D01*
X137700Y104200D01*
X222281Y56187D02*
Y71319D01*
X218100Y75500D02*
X222281Y71319D01*
X123100Y106700D02*
X124900Y108500D01*
X121200Y106700D02*
X123100D01*
X121200Y93401D02*
Y102269D01*
X102532Y100270D02*
X103516Y99286D01*
Y93039D02*
Y99286D01*
X227382Y49954D02*
X228990Y48346D01*
X231476D01*
X227382Y49954D02*
Y51086D01*
X222281Y56187D02*
X227382Y51086D01*
X201300Y35700D02*
X253847D01*
X198025Y41526D02*
X202351Y37200D01*
X237433D01*
X203553Y55116D02*
Y55999D01*
X196000Y41000D02*
X201300Y35700D01*
X253847D02*
X256197Y38050D01*
X237433Y37200D02*
X240705Y40472D01*
X164073Y93039D02*
X199238Y57874D01*
X151154Y93039D02*
Y93725D01*
Y93039D02*
X164073D01*
X199238Y57361D02*
Y57874D01*
X151154Y93725D02*
X152328Y94900D01*
X199238Y57361D02*
X199616Y56984D01*
X215900Y38900D02*
X217870Y40870D01*
X204588Y38900D02*
X215900D01*
X217870Y40870D02*
Y51619D01*
X201775Y41713D02*
X204588Y38900D01*
X217870Y51619D02*
X218456Y52205D01*
X219270D01*
X219800Y52735D01*
Y52939D01*
X142492Y97992D02*
X146000Y101500D01*
X142492Y93039D02*
Y97992D01*
X116508Y93039D02*
Y101492D01*
X116500Y101500D02*
X116508Y101492D01*
X111000Y100651D02*
Y101500D01*
X112177Y93039D02*
Y99474D01*
X111000Y100651D02*
X112177Y99474D01*
X105500Y101500D02*
X107846Y99154D01*
Y93039D02*
Y99154D01*
X102532Y100270D02*
Y102730D01*
X249390Y48346D02*
X251876D01*
X253484Y46739D01*
X255611Y43480D02*
X255611D01*
X253484Y45607D02*
X255611Y43480D01*
X253484Y45607D02*
Y46739D01*
X255611Y43480D02*
X256197Y42895D01*
X196000Y46949D02*
X203175Y54124D01*
X196000Y41000D02*
Y46949D01*
X203362Y55809D02*
X203553Y55999D01*
X203175Y54356D02*
X203362Y54543D01*
X203175Y54124D02*
Y54356D01*
X256197Y38050D02*
Y42895D01*
X203362Y54543D02*
Y55809D01*
X199616Y55999D02*
Y56984D01*
X211600Y50061D02*
Y50265D01*
X212130Y50795D01*
X212944D02*
X213530Y51381D01*
Y54497D01*
X212400Y55627D02*
X213530Y54497D01*
X212130Y50795D02*
X212944D01*
X212400Y55627D02*
Y64631D01*
X220100Y53239D02*
Y64631D01*
X219800Y52939D02*
X220100Y53239D01*
X219800Y49847D02*
X220330Y49317D01*
X220544D01*
X224522Y45339D01*
X219800Y49847D02*
Y50061D01*
X224522Y45339D02*
X237698D01*
X197838Y43591D02*
Y44857D01*
X198025Y45044D01*
X202810Y50061D02*
X211600D01*
X197647Y43401D02*
X197838Y43591D01*
X198025Y45044D02*
Y45276D01*
X202810Y50061D01*
X240705Y48346D02*
X249390D01*
X237698Y45339D02*
X240705Y48346D01*
X197647Y42417D02*
Y43401D01*
Y42417D02*
X198025Y42039D01*
Y41526D02*
Y42039D01*
X240705Y40472D02*
X249390D01*
X138161Y99161D02*
X140500Y101500D01*
X138161Y93039D02*
Y99161D01*
X120839Y93039D02*
X121200Y93401D01*
X222128Y40472D02*
X231476D01*
X222100Y40500D02*
X222128Y40472D01*
X201775Y41713D02*
Y43210D01*
X240644Y79963D02*
X245228Y84548D01*
X240430Y79963D02*
X240644D01*
X239900Y79220D02*
Y79434D01*
X245228Y84548D02*
X249100D01*
X239900Y79434D02*
X240430Y79963D01*
X249100Y78052D02*
X249390Y77762D01*
Y56221D02*
Y77762D01*
X147400Y96846D02*
X148954Y98400D01*
X147400Y93616D02*
Y96846D01*
X146823Y93039D02*
X147400Y93616D01*
X201584Y43401D02*
X201775Y43210D01*
X199616Y56984D02*
X199994Y57361D01*
Y57874D01*
X200694Y58574D02*
X205965D01*
X210856Y53683D01*
X211070D02*
X211600Y53153D01*
Y52939D02*
Y53153D01*
X210856Y53683D02*
X211070D01*
X199994Y57874D02*
X200694Y58574D01*
D56*
X83071Y61543D02*
Y62148D01*
X82300Y62500D02*
X82719D01*
X83362Y61253D02*
X84299D01*
X83071Y61543D02*
X83362Y61253D01*
X82719Y62500D02*
X83071Y62148D01*
D57*
X127697Y100531D02*
X128220Y100008D01*
X127697Y100531D02*
X133500D01*
X127539Y100689D02*
X127697Y100531D01*
X128220Y99968D02*
X129500Y98689D01*
Y93039D02*
Y98689D01*
X128220Y99968D02*
Y100008D01*
D58*
X215400Y47200D02*
D03*
X198300Y65800D02*
D03*
X187200Y65700D02*
D03*
X75800Y74400D02*
D03*
X87968Y80005D02*
D03*
X83568D02*
D03*
X79232Y80753D02*
D03*
X80035Y74573D02*
D03*
X84391Y75195D02*
D03*
X88791D02*
D03*
X18874Y81741D02*
D03*
X17342Y77617D02*
D03*
X19368Y73711D02*
D03*
X23616Y72562D02*
D03*
X27335Y74913D02*
D03*
X31689Y75547D02*
D03*
X36089D02*
D03*
X40202Y73983D02*
D03*
X47600Y75200D02*
D03*
X56960Y75547D02*
D03*
X61360D02*
D03*
X65760D02*
D03*
X70160D02*
D03*
X75868Y80753D02*
D03*
X71486Y80358D02*
D03*
X67086D02*
D03*
X62686D02*
D03*
X58286D02*
D03*
X53886D02*
D03*
X49486D02*
D03*
X45088Y80484D02*
D03*
X40689Y80358D02*
D03*
X36289D02*
D03*
X31889D02*
D03*
X27503Y80696D02*
D03*
X23955Y83298D02*
D03*
X108600Y37300D02*
D03*
X116925D02*
D03*
X125250D02*
D03*
X133575D02*
D03*
X141900D02*
D03*
X108700Y29000D02*
D03*
X117025D02*
D03*
X125350D02*
D03*
X133675D02*
D03*
X142000D02*
D03*
X108700Y45700D02*
D03*
X117025D02*
D03*
X125350D02*
D03*
X133675D02*
D03*
X142000D02*
D03*
X108700Y54100D02*
D03*
X117025D02*
D03*
X125350D02*
D03*
X133675D02*
D03*
X142000D02*
D03*
X108600Y62100D02*
D03*
X116925D02*
D03*
X125250D02*
D03*
X133575D02*
D03*
X141900D02*
D03*
X108600Y70400D02*
D03*
X116925D02*
D03*
X125250D02*
D03*
X133575D02*
D03*
X141900D02*
D03*
Y78800D02*
D03*
X133575D02*
D03*
X125250D02*
D03*
X116925D02*
D03*
X108600D02*
D03*
X259467Y120459D02*
D03*
Y110459D02*
D03*
Y100459D02*
D03*
Y90459D02*
D03*
Y80459D02*
D03*
Y70459D02*
D03*
Y60459D02*
D03*
Y50459D02*
D03*
Y40459D02*
D03*
Y30459D02*
D03*
Y20459D02*
D03*
Y10459D02*
D03*
X249467Y100459D02*
D03*
Y90459D02*
D03*
Y20459D02*
D03*
X239467Y120459D02*
D03*
Y110459D02*
D03*
Y100459D02*
D03*
Y90459D02*
D03*
Y60459D02*
D03*
Y50459D02*
D03*
Y20459D02*
D03*
Y10459D02*
D03*
X229467Y120459D02*
D03*
Y110459D02*
D03*
Y100459D02*
D03*
Y90459D02*
D03*
Y80459D02*
D03*
Y70459D02*
D03*
Y60459D02*
D03*
Y10459D02*
D03*
X219467Y120459D02*
D03*
Y110459D02*
D03*
Y100459D02*
D03*
Y90459D02*
D03*
X209467Y120459D02*
D03*
Y110459D02*
D03*
Y100459D02*
D03*
Y60459D02*
D03*
X199467Y120459D02*
D03*
Y110459D02*
D03*
Y80459D02*
D03*
Y30459D02*
D03*
X189467Y120459D02*
D03*
Y90459D02*
D03*
Y80459D02*
D03*
Y60459D02*
D03*
Y50459D02*
D03*
Y40459D02*
D03*
Y30459D02*
D03*
Y10459D02*
D03*
X179467Y120459D02*
D03*
Y90459D02*
D03*
Y60459D02*
D03*
Y50459D02*
D03*
Y40459D02*
D03*
Y20459D02*
D03*
X169467Y120459D02*
D03*
Y80459D02*
D03*
Y60459D02*
D03*
Y50459D02*
D03*
Y30459D02*
D03*
Y20459D02*
D03*
X159467Y120459D02*
D03*
Y90459D02*
D03*
Y80459D02*
D03*
Y70459D02*
D03*
Y40459D02*
D03*
Y30459D02*
D03*
Y20459D02*
D03*
X149467Y120459D02*
D03*
Y20459D02*
D03*
X139467Y120459D02*
D03*
Y20459D02*
D03*
X129467Y120459D02*
D03*
Y20459D02*
D03*
X119467Y120459D02*
D03*
Y110459D02*
D03*
Y20459D02*
D03*
X109467Y120459D02*
D03*
Y20459D02*
D03*
X99467Y120459D02*
D03*
Y110459D02*
D03*
Y20459D02*
D03*
X89467Y120459D02*
D03*
Y110459D02*
D03*
Y100459D02*
D03*
Y90459D02*
D03*
Y50459D02*
D03*
Y40459D02*
D03*
Y30459D02*
D03*
Y10459D02*
D03*
X79467Y120459D02*
D03*
Y110459D02*
D03*
Y100459D02*
D03*
Y90459D02*
D03*
Y20459D02*
D03*
Y10459D02*
D03*
X69467Y120459D02*
D03*
Y110459D02*
D03*
Y100459D02*
D03*
Y90459D02*
D03*
Y50459D02*
D03*
Y40459D02*
D03*
Y20459D02*
D03*
X59467Y120459D02*
D03*
Y110459D02*
D03*
Y100459D02*
D03*
Y90459D02*
D03*
Y10459D02*
D03*
X49467Y120459D02*
D03*
Y110459D02*
D03*
Y100459D02*
D03*
Y90459D02*
D03*
Y40459D02*
D03*
Y30459D02*
D03*
Y20459D02*
D03*
Y10459D02*
D03*
X39467Y120459D02*
D03*
Y110459D02*
D03*
Y100459D02*
D03*
Y90459D02*
D03*
Y70459D02*
D03*
Y60459D02*
D03*
Y50459D02*
D03*
Y40459D02*
D03*
Y30459D02*
D03*
Y20459D02*
D03*
Y10459D02*
D03*
X29467Y120459D02*
D03*
Y110459D02*
D03*
Y100459D02*
D03*
Y70459D02*
D03*
Y60459D02*
D03*
Y50459D02*
D03*
Y40459D02*
D03*
Y30459D02*
D03*
Y20459D02*
D03*
Y10459D02*
D03*
X19467Y120459D02*
D03*
Y110459D02*
D03*
Y100459D02*
D03*
Y60459D02*
D03*
Y50459D02*
D03*
Y40459D02*
D03*
Y30459D02*
D03*
Y20459D02*
D03*
X9467Y100459D02*
D03*
Y90459D02*
D03*
Y80459D02*
D03*
Y70459D02*
D03*
Y60459D02*
D03*
Y50459D02*
D03*
Y40459D02*
D03*
Y30459D02*
D03*
Y20459D02*
D03*
X193900Y56000D02*
D03*
X225100Y61200D02*
D03*
X67900Y59000D02*
D03*
X56600Y49000D02*
D03*
X62800Y56700D02*
D03*
X65561Y53239D02*
D03*
X54800Y63300D02*
D03*
X69500Y66300D02*
D03*
X208600Y72100D02*
D03*
X137700Y104200D02*
D03*
Y111200D02*
D03*
X217400Y80000D02*
D03*
X121200Y102269D02*
D03*
Y106700D02*
D03*
X207517Y32817D02*
D03*
X217200Y72100D02*
D03*
X207517Y43428D02*
D03*
X222100Y40500D02*
D03*
M02*
